# BASEBOARD_FAB2 (Tioga Pass) — schematic netlist excerpt (pin names and nets, part order shuffled) for the footprints in the layout excerpt that follows; sources: Cadence DE-HDL packaged netlist, KiCad conversion of Wiwynn_Tioga_Pass_MB.brd

J9T1  SCONN288_H44441003  SCONN  pkg PIP  page 78
  \12v\(1)  = P12V_NVDIMM_GHJ
  VSS(93)  = GND
  DQ(4)  = M_G_DQ<4>
  VSS(92)  = GND
  DQ(0)  = M_G_DQ<0>
  VSS(91)  = GND
  DQS9P  = M_G_DQS_DP<9>
  DQS9N  = M_G_DQS_DN<9>
  VSS(90)  = GND
  DQ(6)  = M_G_DQ<6>
  VSS(89)  = GND
  DQ(2)  = M_G_DQ<2>
  VSS(88)  = GND
  DQ(12)  = M_G_DQ<12>
  VSS(87)  = GND
  DQ(8)  = M_G_DQ<8>
  VSS(86)  = GND
  DQS10P  = M_G_DQS_DP<10>
  DQS10N  = M_G_DQS_DN<10>
  VSS(85)  = GND
  DQ(14)  = M_G_DQ<14>
  VSS(84)  = GND
  DQ(10)  = M_G_DQ<10>
  VSS(83)  = GND
  DQ(20)  = M_G_DQ<20>
  VSS(82)  = GND
  DQ(16)  = M_G_DQ<16>
  VSS(81)  = GND
  DQS11P  = M_G_DQS_DP<11>
  DQS11N  = M_G_DQS_DN<11>
  VSS(80)  = GND
  DQ(22)  = M_G_DQ<22>
  VSS(79)  = GND
  DQ(18)  = M_G_DQ<18>
  VSS(78)  = GND
  DQ(28)  = M_G_DQ<28>
  VSS(77)  = GND
  DQ(24)  = M_G_DQ<24>
  VSS(76)  = GND
  DQS12P  = M_G_DQS_DP<12>
  DQS12N  = M_G_DQS_DN<12>
  VSS(75)  = GND
  DQ(30)  = M_G_DQ<30>
  VSS(74)  = GND
  DQ(26)  = M_G_DQ<26>
  VSS(73)  = GND
  CB(4)  = M_G_ECC<4>
  VSS(72)  = GND
  CB(0)  = M_G_ECC<0>
  VSS(71)  = GND
  DQS17P  = M_G_DQS_DP<17>
  DQS17N  = M_G_DQS_DN<17>
  VSS(70)  = GND
  CB(6)  = M_G_ECC<6>
  VSS(69)  = GND
  CB(2)  = M_G_ECC<2>
  VSS(68)  = GND
  RESET_N  = M_GHJ_RST_N
  VDD(25)  = PVDDQ_GHJ
  CKE(0)  = M_G_CKE<2>
  VDD(24)  = PVDDQ_GHJ
  ACT_N  = M_G_ACT_N
  BG(0)  = M_G_BG<0>
  VDD(23)  = PVDDQ_GHJ
  A12  = M_G_MA<12>
  A9  = M_G_MA<9>
  VDD(22)  = PVDDQ_GHJ
  A8  = M_G_MA<8>
  A6  = M_G_MA<6>
  VDD(21)  = PVDDQ_GHJ
  A3  = M_G_MA<3>
  A1  = M_G_MA<1>
  VDD(20)  = PVDDQ_GHJ
  CK0P  = M_G_CLK_DP<2>
  CK0N  = M_G_CLK_DN<2>
  VDD(19)  = PVDDQ_GHJ
  VTT(1)  = PVTT_GHJ
  EVENT_N  = FM_DIMM_EVENT_COD_N
  A0  = M_G_MA<0>
  VDD(18)  = PVDDQ_GHJ
  BA(0)  = M_G_BA<0>
  A16_RAS_N  = M_G_MA<16>
  VDD(17)  = PVDDQ_GHJ
  S0_N  = M_G_CS_N<4>
  VDD(16)  = PVDDQ_GHJ
  A15_CAS_N  = M_G_MA<15>
  ODT(0)  = M_G_ODT<2>
  VDD(15)  = PVDDQ_GHJ
  S1_N  = M_G_CS_N<5>
  VDD(14)  = PVDDQ_GHJ
  ODT(1)  = M_G_ODT<3>
  VDD(13)  = PVDDQ_GHJ
  S2_N_C(0)  = M_G_CS_N<6>
  VSS(67)  = GND
  DQ(36)  = M_G_DQ<36>
  VSS(66)  = GND
  DQ(32)  = M_G_DQ<32>
  VSS(65)  = GND
  DQS13P  = M_G_DQS_DP<13>
  DQS13N  = M_G_DQS_DN<13>
  VSS(64)  = GND
  DQ(38)  = M_G_DQ<38>
  VSS(63)  = GND
  DQ(34)  = M_G_DQ<34>
  VSS(62)  = GND
  DQ(44)  = M_G_DQ<44>
  VSS(61)  = GND
  DQ(40)  = M_G_DQ<40>
  VSS(60)  = GND
  DQS14P  = M_G_DQS_DP<14>
  DQS14N  = M_G_DQS_DN<14>
  VSS(59)  = GND
  DQ(46)  = M_G_DQ<46>
  VSS(58)  = GND
  DQ(42)  = M_G_DQ<42>
  VSS(57)  = GND
  DQ(52)  = M_G_DQ<52>
  VSS(56)  = GND
  DQ(48)  = M_G_DQ<48>
  VSS(55)  = GND
  DQS15P  = M_G_DQS_DP<15>
  DQS15N  = M_G_DQS_DN<15>
  VSS(54)  = GND
  DQ(54)  = M_G_DQ<54>
  VSS(53)  = GND
  DQ(50)  = M_G_DQ<50>
  VSS(52)  = GND
  DQ(60)  = M_G_DQ<60>
  VSS(51)  = GND
  DQ(56)  = M_G_DQ<56>
  VSS(50)  = GND
  DQS16P  = M_G_DQS_DP<16>
  DQS16N  = M_G_DQS_DN<16>
  VSS(49)  = GND
  DQ(62)  = M_G_DQ<62>
  VSS(48)  = GND
  DQ(58)  = M_G_DQ<58>
  VSS(47)  = GND
  SA(0)  = PVPP_GHJ
  SA(1)  = GND
  SCL  = SMB_DDR_GHJ_VPP_SCL
  VPP(4)  = PVPP_GHJ
  VPP(3)  = PVPP_GHJ
  RFU(2)  = TP_CH_G_DIMM0_RFU_2
  \12v\(0)  = P12V_NVDIMM_GHJ
  VREFCA  = M_G_VREF
  VSS(46)  = GND
  DQ(5)  = M_G_DQ<5>
  VSS(45)  = GND
  DQ(1)  = M_G_DQ<1>
  VSS(44)  = GND
  DQS0N  = M_G_DQS_DN<0>
  DQS0P  = M_G_DQS_DP<0>
  VSS(43)  = GND
  DQ(7)  = M_G_DQ<7>
  VSS(42)  = GND
  DQ(3)  = M_G_DQ<3>
  VSS(41)  = GND
  DQ(13)  = M_G_DQ<13>
  VSS(40)  = GND
  DQ(9)  = M_G_DQ<9>
  VSS(39)  = GND
  DQS1N  = M_G_DQS_DN<1>
  DQS1P  = M_G_DQS_DP<1>
  VSS(38)  = GND
  DQ(15)  = M_G_DQ<15>
  VSS(37)  = GND
  DQ(11)  = M_G_DQ<11>
  VSS(36)  = GND
  DQ(21)  = M_G_DQ<21>
  VSS(35)  = GND
  DQ(17)  = M_G_DQ<17>
  VSS(34)  = GND
  DQS2N  = M_G_DQS_DN<2>
  DQS2P  = M_G_DQS_DP<2>
  VSS(33)  = GND
  DQ(23)  = M_G_DQ<23>
  VSS(32)  = GND
  DQ(19)  = M_G_DQ<19>
  VSS(31)  = GND
  DQ(29)  = M_G_DQ<29>
  VSS(30)  = GND
  DQ(25)  = M_G_DQ<25>
  VSS(29)  = GND
  DQS3N  = M_G_DQS_DN<3>
  DQS3P  = M_G_DQS_DP<3>
  VSS(28)  = GND
  DQ(31)  = M_G_DQ<31>
  VSS(27)  = GND
  DQ(27)  = M_G_DQ<27>
  VSS(26)  = GND
  CB(5)  = M_G_ECC<5>
  VSS(25)  = GND
  CB(1)  = M_G_ECC<1>
  VSS(24)  = GND
  DQS8N  = M_G_DQS_DN<8>
  DQS8P  = M_G_DQS_DP<8>
  VSS(23)  = GND
  CB(7)  = M_G_ECC<7>
  VSS(22)  = GND
  CB(3)  = M_G_ECC<3>
  VSS(21)  = GND
  CKE(1)  = M_G_CKE<3>
  VDD(12)  = PVDDQ_GHJ
  RFU(0)  = TP_CH_G_DIMM0_RFU_0
  VDD(11)  = PVDDQ_GHJ
  BG(1)  = M_G_BG<1>
  ALERT_N  = M_G_ALERT_N
  VDD(10)  = PVDDQ_GHJ
  A11  = M_G_MA<11>
  A7  = M_G_MA<7>
  VDD(9)  = PVDDQ_GHJ
  A5  = M_G_MA<5>
  A4  = M_G_MA<4>
  VDD(8)  = PVDDQ_GHJ
  A2  = M_G_MA<2>
  VDD(7)  = PVDDQ_GHJ
  CK1P  = M_G_CLK_DP<3>
  CK1N  = M_G_CLK_DN<3>
  VDD(6)  = PVDDQ_GHJ
  VTT(0)  = PVTT_GHJ
  PAR  = M_G_PAR
  VDD(5)  = PVDDQ_GHJ
  BA(1)  = M_G_BA<1>
  A10  = M_G_MA<10>
  VDD(4)  = PVDDQ_GHJ
  RFU(1)  = TP_CH_G_DIMM0_RFU_1
  A14_WE_N  = M_G_MA<14>
  VDD(3)  = PVDDQ_GHJ
  SAVE_N_NC  = FM_ADR_COMPLETE_GHJ_N
  VDD(2)  = PVDDQ_GHJ
  A13  = M_G_MA<13>
  VDD(1)  = PVDDQ_GHJ
  A17  = M_G_MA<17>
  C(2)  = M_G_C<2>
  VDD(0)  = PVDDQ_GHJ
  S3_N_C(1)  = M_G_CS_N<7>
  SA(2)  = GND
  VSS(20)  = GND
  DQ(37)  = M_G_DQ<37>
  VSS(19)  = GND
  DQ(33)  = M_G_DQ<33>
  VSS(18)  = GND
  DQS4N  = M_G_DQS_DN<4>
  DQS4P  = M_G_DQS_DP<4>
  VSS(17)  = GND
  DQ(39)  = M_G_DQ<39>
  VSS(16)  = GND
  DQ(35)  = M_G_DQ<35>
  VSS(15)  = GND
  DQ(45)  = M_G_DQ<45>
  VSS(14)  = GND
  DQ(41)  = M_G_DQ<41>
  VSS(13)  = GND
  DQS5N  = M_G_DQS_DN<5>
  DQS5P  = M_G_DQS_DP<5>
  VSS(12)  = GND
  DQ(47)  = M_G_DQ<47>
  VSS(11)  = GND
  DQ(43)  = M_G_DQ<43>
  VSS(10)  = GND
  DQ(53)  = M_G_DQ<53>
  VSS(9)  = GND
  DQ(49)  = M_G_DQ<49>
  VSS(8)  = GND
  DQS6N  = M_G_DQS_DN<6>
  DQS6P  = M_G_DQS_DP<6>
  VSS(7)  = GND
  DQ(55)  = M_G_DQ<55>
  VSS(6)  = GND
  DQ(51)  = M_G_DQ<51>
  VSS(5)  = GND
  DQ(61)  = M_G_DQ<61>
  VSS(4)  = GND
  DQ(57)  = M_G_DQ<57>
  VSS(3)  = GND
  DQS7N  = M_G_DQS_DN<7>
  DQS7P  = M_G_DQS_DP<7>
  VSS(2)  = GND
  DQ(63)  = M_G_DQ<63>
  VSS(1)  = GND
  DQ(59)  = M_G_DQ<59>
  VSS(0)  = GND
  VDDSPD  = PVPP_GHJ
  SDA  = SMB_DDR_GHJ_VPP_SDA
  VPP(1)  = PVPP_GHJ
  VPP(0)  = PVPP_GHJ
  VPP(2)  = PVPP_GHJ

(kicad_pcb
	(version 20260206)
	(generator "pcbnew")
	(generator_version "10.0")
	(general
		(thickness 1.6)
		(legacy_teardrops no)
	)
	(paper "A4")
	(title_block
		(title "Wiwynn_Tioga_Pass_MB.brd")
		(comment 1 "Tioga Pass / footprint 4084 of 4770 (J9T1), pads 250-291 of 291")
	)
	(layers
		(0 "F.Cu" signal "TOP")
		(4 "In1.Cu" signal "L2GND")
		(6 "In2.Cu" signal "L3")
		(8 "In3.Cu" signal "L4GND")
		(10 "In4.Cu" signal "L5")
		(12 "In5.Cu" signal "L6GND")
		(14 "In6.Cu" signal "L7VCC")
		(16 "In7.Cu" signal "L8VCC")
		(18 "In8.Cu" signal "L9GND")
		(20 "In9.Cu" signal "L10")
		(22 "In10.Cu" signal "L11GND")
		(24 "In11.Cu" signal "L12")
		(26 "In12.Cu" signal "L13GND")
		(2 "B.Cu" signal "BOTTOM")
		(9 "F.Adhes" user "F.Adhesive")
		(11 "B.Adhes" user "B.Adhesive")
		(13 "F.Paste" user "Package Geometry/Pastemask Top")
		(15 "B.Paste" user "Package Geometry/Pastemask Bottom")
		(5 "F.SilkS" user "Ref Des/Silkscreen Top")
		(7 "B.SilkS" user "Ref Des/Silkscreen Bottom")
		(1 "F.Mask" user "Board Geometry/Soldermask Top")
		(3 "B.Mask" user "Board Geometry/Soldermask Bottom")
		(17 "Dwgs.User" user "User.Drawings")
		(19 "Cmts.User" user "User.Comments")
		(21 "Eco1.User" user "User.Eco1")
		(23 "Eco2.User" user "User.Eco2")
		(25 "Edge.Cuts" user "Board Geometry/Outline")
		(27 "Margin" user)
		(31 "F.CrtYd" user "Package Geometry/Place Bound Top")
		(29 "B.CrtYd" user "Package Geometry/Place Bound Bottom")
		(35 "F.Fab" user "Ref Des/Assembly Top")
		(33 "B.Fab" user "Ref Des/Assembly Bottom")
	)
	(footprint ""
		(layer "B.Cu")
		(at 29.699458 -24.824182 90)
		(property "Reference" "J9T1"
			(at 2.200148 39.261542 0)
			(unlocked yes)
			(layer "B.SilkS")
			(effects
				(font
					(size 0.7874 0.5842)
					(thickness 0.1524)
				)
				(justify left mirror)
			)
		)
		(property "Value" ""
			(at 0 0 90)
			(layer "B.Fab")
			(effects
				(font
					(size 1.27 1.27)
				)
				(justify mirror)
			)
		)
		(duplicate_pad_numbers_are_jumpers no)
		(pad "247" smd rect
			(at -4.59994 91.799918 270)
			(size 1.8034 0.508)
			(layers "B.Cu" "B.Mask" "B.Paste")
			(net "M_G_DQ<39>")
		)
		(pad "248" smd rect
			(at -4.59994 92.650056 270)
			(size 1.8034 0.508)
			(layers "B.Cu" "B.Mask" "B.Paste")
			(net "GND")
		)
		(pad "249" smd rect
			(at -4.59994 93.49994 270)
			(size 1.8034 0.508)
			(layers "B.Cu" "B.Mask" "B.Paste")
			(net "M_G_DQ<35>")
		)
		(pad "250" smd rect
			(at -4.59994 94.350078 270)
			(size 1.8034 0.508)
			(layers "B.Cu" "B.Mask" "B.Paste")
			(net "GND")
		)
		(pad "251" smd rect
			(at -4.59994 95.199962 270)
			(size 1.8034 0.508)
			(layers "B.Cu" "B.Mask" "B.Paste")
			(net "M_G_DQ<45>")
		)
		(pad "252" smd rect
			(at -4.59994 96.0501 270)
			(size 1.8034 0.508)
			(layers "B.Cu" "B.Mask" "B.Paste")
			(net "GND")
		)
		(pad "253" smd rect
			(at -4.59994 96.899984 270)
			(size 1.8034 0.508)
			(layers "B.Cu" "B.Mask" "B.Paste")
			(net "M_G_DQ<41>")
		)
		(pad "254" smd rect
			(at -4.59994 97.750122 270)
			(size 1.8034 0.508)
			(layers "B.Cu" "B.Mask" "B.Paste")
			(net "GND")
		)
		(pad "255" smd rect
			(at -4.59994 98.600006 270)
			(size 1.8034 0.508)
			(layers "B.Cu" "B.Mask" "B.Paste")
			(net "M_G_DQS_DN<5>")
		)
		(pad "256" smd rect
			(at -4.59994 99.44989 270)
			(size 1.8034 0.508)
			(layers "B.Cu" "B.Mask" "B.Paste")
			(net "M_G_DQS_DP<5>")
		)
		(pad "257" smd rect
			(at -4.59994 100.300028 270)
			(size 1.8034 0.508)
			(layers "B.Cu" "B.Mask" "B.Paste")
			(net "GND")
		)
		(pad "258" smd rect
			(at -4.59994 101.149912 270)
			(size 1.8034 0.508)
			(layers "B.Cu" "B.Mask" "B.Paste")
			(net "M_G_DQ<47>")
		)
		(pad "259" smd rect
			(at -4.59994 102.00005 270)
			(size 1.8034 0.508)
			(layers "B.Cu" "B.Mask" "B.Paste")
			(net "GND")
		)
		(pad "260" smd rect
			(at -4.59994 102.849934 270)
			(size 1.8034 0.508)
			(layers "B.Cu" "B.Mask" "B.Paste")
			(net "M_G_DQ<43>")
		)
		(pad "261" smd rect
			(at -4.59994 103.700072 270)
			(size 1.8034 0.508)
			(layers "B.Cu" "B.Mask" "B.Paste")
			(net "GND")
		)
		(pad "262" smd rect
			(at -4.59994 104.549956 270)
			(size 1.8034 0.508)
			(layers "B.Cu" "B.Mask" "B.Paste")
			(net "M_G_DQ<53>")
		)
		(pad "263" smd rect
			(at -4.59994 105.400094 270)
			(size 1.8034 0.508)
			(layers "B.Cu" "B.Mask" "B.Paste")
			(net "GND")
		)
		(pad "264" smd rect
			(at -4.59994 106.249978 270)
			(size 1.8034 0.508)
			(layers "B.Cu" "B.Mask" "B.Paste")
			(net "M_G_DQ<49>")
		)
		(pad "265" smd rect
			(at -4.59994 107.100116 270)
			(size 1.8034 0.508)
			(layers "B.Cu" "B.Mask" "B.Paste")
			(net "GND")
		)
		(pad "266" smd rect
			(at -4.59994 107.95 270)
			(size 1.8034 0.508)
			(layers "B.Cu" "B.Mask" "B.Paste")
			(net "M_G_DQS_DN<6>")
		)
		(pad "267" smd rect
			(at -4.59994 108.799884 270)
			(size 1.8034 0.508)
			(layers "B.Cu" "B.Mask" "B.Paste")
			(net "M_G_DQS_DP<6>")
		)
		(pad "268" smd rect
			(at -4.59994 109.650022 270)
			(size 1.8034 0.508)
			(layers "B.Cu" "B.Mask" "B.Paste")
			(net "GND")
		)
		(pad "269" smd rect
			(at -4.59994 110.499906 270)
			(size 1.8034 0.508)
			(layers "B.Cu" "B.Mask" "B.Paste")
			(net "M_G_DQ<55>")
		)
		(pad "270" smd rect
			(at -4.59994 111.350044 270)
			(size 1.8034 0.508)
			(layers "B.Cu" "B.Mask" "B.Paste")
			(net "GND")
		)
		(pad "271" smd rect
			(at -4.59994 112.199928 270)
			(size 1.8034 0.508)
			(layers "B.Cu" "B.Mask" "B.Paste")
			(net "M_G_DQ<51>")
		)
		(pad "272" smd rect
			(at -4.59994 113.050066 270)
			(size 1.8034 0.508)
			(layers "B.Cu" "B.Mask" "B.Paste")
			(net "GND")
		)
		(pad "273" smd rect
			(at -4.59994 113.89995 270)
			(size 1.8034 0.508)
			(layers "B.Cu" "B.Mask" "B.Paste")
			(net "M_G_DQ<61>")
		)
		(pad "274" smd rect
			(at -4.59994 114.750088 270)
			(size 1.8034 0.508)
			(layers "B.Cu" "B.Mask" "B.Paste")
			(net "GND")
		)
		(pad "275" smd rect
			(at -4.59994 115.599972 270)
			(size 1.8034 0.508)
			(layers "B.Cu" "B.Mask" "B.Paste")
			(net "M_G_DQ<57>")
		)
		(pad "276" smd rect
			(at -4.59994 116.45011 270)
			(size 1.8034 0.508)
			(layers "B.Cu" "B.Mask" "B.Paste")
			(net "GND")
		)
		(pad "277" smd rect
			(at -4.59994 117.299994 270)
			(size 1.8034 0.508)
			(layers "B.Cu" "B.Mask" "B.Paste")
			(net "M_G_DQS_DN<7>")
		)
		(pad "278" smd rect
			(at -4.59994 118.149878 270)
			(size 1.8034 0.508)
			(layers "B.Cu" "B.Mask" "B.Paste")
			(net "M_G_DQS_DP<7>")
		)
		(pad "279" smd rect
			(at -4.59994 119.000016 270)
			(size 1.8034 0.508)
			(layers "B.Cu" "B.Mask" "B.Paste")
			(net "GND")
		)
		(pad "280" smd rect
			(at -4.59994 119.8499 270)
			(size 1.8034 0.508)
			(layers "B.Cu" "B.Mask" "B.Paste")
			(net "M_G_DQ<63>")
		)
		(pad "281" smd rect
			(at -4.59994 120.700038 270)
			(size 1.8034 0.508)
			(layers "B.Cu" "B.Mask" "B.Paste")
			(net "GND")
		)
		(pad "282" smd rect
			(at -4.59994 121.549922 270)
			(size 1.8034 0.508)
			(layers "B.Cu" "B.Mask" "B.Paste")
			(net "M_G_DQ<59>")
		)
		(pad "283" smd rect
			(at -4.59994 122.40006 270)
			(size 1.8034 0.508)
			(layers "B.Cu" "B.Mask" "B.Paste")
			(net "GND")
		)
		(pad "284" smd rect
			(at -4.59994 123.249944 270)
			(size 1.8034 0.508)
			(layers "B.Cu" "B.Mask" "B.Paste")
			(net "PVPP_GHJ")
		)
		(pad "285" smd rect
			(at -4.59994 124.100082 270)
			(size 1.8034 0.508)
			(layers "B.Cu" "B.Mask" "B.Paste")
			(net "SMB_DDR_GHJ_VPP_SDA")
		)
		(pad "286" smd rect
			(at -4.59994 124.949966 270)
			(size 1.8034 0.508)
			(layers "B.Cu" "B.Mask" "B.Paste")
			(net "PVPP_GHJ")
		)
		(pad "287" smd rect
			(at -4.59994 125.800104 270)
			(size 1.8034 0.508)
			(layers "B.Cu" "B.Mask" "B.Paste")
			(net "PVPP_GHJ")
		)
		(pad "288" smd rect
			(at -4.59994 126.649988 270)
			(size 1.8034 0.508)
			(layers "B.Cu" "B.Mask" "B.Paste")
			(net "PVPP_GHJ")
		)
	)
)
